# OCuLink to PCIe adapter — KiCad project settings (.kicad_pro: net classes, design rules, text variables)
{
  "board": {
    "3dviewports": [],
    "design_settings": {
      "defaults": {
        "apply_defaults_to_fp_fields": false,
        "apply_defaults_to_fp_shapes": false,
        "apply_defaults_to_fp_text": false,
        "board_outline_line_width": 0.05,
        "copper_line_width": 0.2,
        "copper_text_italic": false,
        "copper_text_size_h": 1.5,
        "copper_text_size_v": 1.5,
        "copper_text_thickness": 0.3,
        "copper_text_upright": false,
        "courtyard_line_width": 0.05,
        "dimension_precision": 4,
        "dimension_units": 3,
        "dimensions": {
          "arrow_length": 1270000,
          "extension_offset": 500000,
          "keep_text_aligned": true,
          "suppress_zeroes": true,
          "text_position": 0,
          "units_format": 0
        },
        "fab_line_width": 0.1,
        "fab_text_italic": false,
        "fab_text_size_h": 1.0,
        "fab_text_size_v": 1.0,
        "fab_text_thickness": 0.15,
        "fab_text_upright": false,
        "other_line_width": 0.1,
        "other_text_italic": false,
        "other_text_size_h": 1.0,
        "other_text_size_v": 1.0,
        "other_text_thickness": 0.15,
        "other_text_upright": false,
        "pads": {
          "drill": 3.2,
          "height": 6.0,
          "width": 6.0
        },
        "silk_line_width": 0.1,
        "silk_text_italic": false,
        "silk_text_size_h": 1.0,
        "silk_text_size_v": 1.0,
        "silk_text_thickness": 0.1,
        "silk_text_upright": false,
        "zones": {
          "min_clearance": 0.15
        }
      },
      "diff_pair_dimensions": [
        {
          "gap": 0.0,
          "via_gap": 0.0,
          "width": 0.0
        }
      ],
      "drc_exclusions": [],
      "meta": {
        "version": 2
      },
      "rule_severities": {
        "annular_width": "error",
        "clearance": "error",
        "connection_width": "warning",
        "copper_edge_clearance": "error",
        "copper_sliver": "warning",
        "courtyards_overlap": "error",
        "creepage": "error",
        "diff_pair_gap_out_of_range": "error",
        "diff_pair_uncoupled_length_too_long": "error",
        "drill_out_of_range": "error",
        "duplicate_footprints": "warning",
        "extra_footprint": "warning",
        "footprint": "error",
        "footprint_filters_mismatch": "warning",
        "footprint_symbol_mismatch": "warning",
        "footprint_type_mismatch": "ignore",
        "hole_clearance": "error",
        "hole_to_hole": "error",
        "holes_co_located": "error",
        "invalid_outline": "error",
        "isolated_copper": "warning",
        "item_on_disabled_layer": "error",
        "items_not_allowed": "error",
        "length_out_of_range": "error",
        "lib_footprint_issues": "warning",
        "lib_footprint_mismatch": "warning",
        "malformed_courtyard": "error",
        "microvia_drill_out_of_range": "error",
        "mirrored_text_on_front_layer": "warning",
        "missing_courtyard": "warning",
        "missing_footprint": "warning",
        "net_conflict": "warning",
        "nonmirrored_text_on_back_layer": "warning",
        "npth_inside_courtyard": "warning",
        "padstack": "warning",
        "pth_inside_courtyard": "warning",
        "shorting_items": "error",
        "silk_edge_clearance": "warning",
        "silk_over_copper": "warning",
        "silk_overlap": "warning",
        "skew_out_of_range": "error",
        "solder_mask_bridge": "error",
        "starved_thermal": "error",
        "text_height": "warning",
        "text_on_edge_cuts": "error",
        "text_thickness": "warning",
        "through_hole_pad_without_hole": "error",
        "too_many_vias": "error",
        "track_angle": "error",
        "track_dangling": "warning",
        "track_segment_length": "error",
        "track_width": "error",
        "tracks_crossing": "error",
        "unconnected_items": "error",
        "unresolved_variable": "error",
        "via_dangling": "warning",
        "zones_intersect": "error"
      },
      "rules": {
        "max_error": 0.005,
        "min_clearance": 0.125,
        "min_connection": 0.125,
        "min_copper_edge_clearance": 0.4,
        "min_groove_width": 0.0,
        "min_hole_clearance": 0.125,
        "min_hole_to_hole": 0.25,
        "min_microvia_diameter": 0.1,
        "min_microvia_drill": 0.25,
        "min_resolved_spokes": 1,
        "min_silk_clearance": 0.0,
        "min_text_height": 0.6,
        "min_text_thickness": 0.12,
        "min_through_hole_diameter": 0.1,
        "min_track_width": 0.125,
        "min_via_annular_width": 0.125,
        "min_via_diameter": 0.45,
        "solder_mask_to_copper_clearance": 0.0,
        "use_height_for_length_calcs": true
      },
      "teardrop_options": [
        {
          "td_onpthpad": true,
          "td_onroundshapesonly": false,
          "td_onsmdpad": true,
          "td_ontrackend": false,
          "td_onvia": true
        }
      ],
      "teardrop_parameters": [
        {
          "td_allow_use_two_tracks": true,
          "td_curve_segcount": 0,
          "td_height_ratio": 1.0,
          "td_length_ratio": 0.5,
          "td_maxheight": 2.0,
          "td_maxlen": 1.0,
          "td_on_pad_in_zone": false,
          "td_target_name": "td_round_shape",
          "td_width_to_size_filter_ratio": 0.9
        },
        {
          "td_allow_use_two_tracks": true,
          "td_curve_segcount": 0,
          "td_height_ratio": 1.0,
          "td_length_ratio": 0.5,
          "td_maxheight": 2.0,
          "td_maxlen": 1.0,
          "td_on_pad_in_zone": false,
          "td_target_name": "td_rect_shape",
          "td_width_to_size_filter_ratio": 0.9
        },
        {
          "td_allow_use_two_tracks": true,
          "td_curve_segcount": 0,
          "td_height_ratio": 1.0,
          "td_length_ratio": 0.5,
          "td_maxheight": 2.0,
          "td_maxlen": 1.0,
          "td_on_pad_in_zone": false,
          "td_target_name": "td_track_end",
          "td_width_to_size_filter_ratio": 0.9
        }
      ],
      "track_widths": [
        0.0,
        0.125,
        0.15,
        0.2,
        0.25,
        0.3,
        0.5,
        1.0
      ],
      "tuning_pattern_settings": {
        "diff_pair_defaults": {
          "corner_radius_percentage": 80,
          "corner_style": 1,
          "max_amplitude": 1.0,
          "min_amplitude": 0.2,
          "single_sided": false,
          "spacing": 1.0
        },
        "diff_pair_skew_defaults": {
          "corner_radius_percentage": 80,
          "corner_style": 1,
          "max_amplitude": 1.0,
          "min_amplitude": 0.2,
          "single_sided": false,
          "spacing": 0.6
        },
        "single_track_defaults": {
          "corner_radius_percentage": 80,
          "corner_style": 1,
          "max_amplitude": 1.0,
          "min_amplitude": 0.2,
          "single_sided": false,
          "spacing": 0.6
        }
      },
      "via_dimensions": [
        {
          "diameter": 0.0,
          "drill": 0.0
        },
        {
          "diameter": 0.55,
          "drill": 0.15
        }
      ],
      "zones_allow_external_fillets": false
    },
    "ipc2581": {
      "dist": "",
      "distpn": "",
      "internal_id": "",
      "mfg": "",
      "mpn": ""
    },
    "layer_pairs": [],
    "layer_presets": [],
    "viewports": []
  },
  "boards": [],
  "cvpcb": {
    "equivalence_files": []
  },
  "erc": {
    "erc_exclusions": [],
    "meta": {
      "version": 0
    },
    "pin_map": [
      [
        0,
        0,
        0,
        0,
        0,
        0,
        1,
        0,
        0,
        0,
        0,
        2
      ],
      [
        0,
        2,
        0,
        1,
        0,
        0,
        1,
        0,
        2,
        2,
        2,
        2
      ],
      [
        0,
        0,
        0,
        0,
        0,
        0,
        1,
        0,
        1,
        0,
        1,
        2
      ],
      [
        0,
        1,
        0,
        0,
        0,
        0,
        1,
        1,
        2,
        1,
        1,
        2
      ],
      [
        0,
        0,
        0,
        0,
        0,
        0,
        1,
        0,
        0,
        0,
        0,
        2
      ],
      [
        0,
        0,
        0,
        0,
        0,
        0,
        0,
        0,
        0,
        0,
        0,
        2
      ],
      [
        1,
        1,
        1,
        1,
        1,
        0,
        1,
        1,
        1,
        1,
        1,
        2
      ],
      [
        0,
        0,
        0,
        1,
        0,
        0,
        1,
        0,
        0,
        0,
        0,
        2
      ],
      [
        0,
        2,
        1,
        2,
        0,
        0,
        1,
        0,
        2,
        2,
        2,
        2
      ],
      [
        0,
        2,
        0,
        1,
        0,
        0,
        1,
        0,
        2,
        0,
        0,
        2
      ],
      [
        0,
        2,
        1,
        1,
        0,
        0,
        1,
        0,
        2,
        0,
        0,
        2
      ],
      [
        2,
        2,
        2,
        2,
        2,
        2,
        2,
        2,
        2,
        2,
        2,
        2
      ]
    ],
    "rule_severities": {
      "bus_definition_conflict": "error",
      "bus_entry_needed": "error",
      "bus_to_bus_conflict": "error",
      "bus_to_net_conflict": "error",
      "different_unit_footprint": "error",
      "different_unit_net": "error",
      "duplicate_reference": "error",
      "duplicate_sheet_names": "error",
      "endpoint_off_grid": "warning",
      "extra_units": "error",
      "footprint_filter": "ignore",
      "footprint_link_issues": "warning",
      "four_way_junction": "ignore",
      "global_label_dangling": "warning",
      "hier_label_mismatch": "error",
      "label_dangling": "error",
      "label_multiple_wires": "warning",
      "lib_symbol_issues": "warning",
      "lib_symbol_mismatch": "warning",
      "missing_bidi_pin": "warning",
      "missing_input_pin": "warning",
      "missing_power_pin": "error",
      "missing_unit": "warning",
      "multiple_net_names": "warning",
      "net_not_bus_member": "warning",
      "no_connect_connected": "warning",
      "no_connect_dangling": "warning",
      "pin_not_connected": "error",
      "pin_not_driven": "error",
      "pin_to_pin": "warning",
      "power_pin_not_driven": "error",
      "same_local_global_label": "warning",
      "similar_label_and_power": "warning",
      "similar_labels": "warning",
      "similar_power": "warning",
      "simulation_model_issue": "ignore",
      "single_global_label": "ignore",
      "unannotated": "error",
      "unconnected_wire_endpoint": "warning",
      "unit_value_mismatch": "error",
      "unresolved_variable": "error",
      "wire_dangling": "error"
    }
  },
  "libraries": {
    "pinned_footprint_libs": [],
    "pinned_symbol_libs": []
  },
  "meta": {
    "filename": "oculink-to-pcie-adapter.kicad_pro",
    "version": 3
  },
  "net_settings": {
    "classes": [
      {
        "bus_width": 12,
        "clearance": 0.125,
        "diff_pair_gap": 0.25,
        "diff_pair_via_gap": 0.25,
        "diff_pair_width": 0.2,
        "line_style": 0,
        "microvia_diameter": 0.3,
        "microvia_drill": 0.1,
        "name": "Default",
        "pcb_color": "rgba(0, 0, 0, 0.000)",
        "priority": 2147483647,
        "schematic_color": "rgba(0, 0, 0, 0.000)",
        "track_width": 0.125,
        "via_diameter": 0.45,
        "via_drill": 0.1,
        "wire_width": 6
      },
      {
        "bus_width": 12,
        "clearance": 0.125,
        "diff_pair_gap": 0.2,
        "diff_pair_width": 0.2,
        "line_style": 0,
        "name": "85Ohm-diff_PCIe",
        "pcb_color": "rgb(0, 132, 0)",
        "priority": 2,
        "schematic_color": "rgb(0, 132, 0)",
        "track_width": 0.125,
        "via_diameter": 0.45,
        "via_drill": 0.1,
        "wire_width": 6
      },
      {
        "bus_width": 12,
        "clearance": 0.125,
        "line_style": 0,
        "name": "GND",
        "pcb_color": "rgb(0, 0, 255)",
        "priority": 0,
        "schematic_color": "rgb(0, 0, 255)",
        "track_width": 0.125,
        "via_diameter": 0.45,
        "via_drill": 0.1,
        "wire_width": 6
      },
      {
        "bus_width": 12,
        "clearance": 0.125,
        "line_style": 0,
        "name": "PWR",
        "pcb_color": "rgb(255, 0, 0)",
        "priority": 1,
        "schematic_color": "rgb(255, 0, 0)",
        "track_width": 0.125,
        "via_diameter": 0.45,
        "via_drill": 0.1,
        "wire_width": 6
      }
    ],
    "meta": {
      "version": 4
    },
    "net_colors": null,
    "netclass_assignments": {
      "+12V": [
        "PWR"
      ],
      "+12V_PCIE": [
        "PWR"
      ],
      "+3V3": [
        "PWR"
      ],
      "+3V3_PCIE": [
        "PWR"
      ],
      "/Ideal-diode-1/VIN": [
        "PWR"
      ],
      "/OCuLink/PCIe_{REF0}.CK+": [
        "85Ohm-diff_PCIe"
      ],
      "/OCuLink/PCIe_{REF0}.CK-": [
        "85Ohm-diff_PCIe"
      ],
      "/OCuLink/PCIe_{REF0}_R.CK+": [
        "85Ohm-diff_PCIe"
      ],
      "/OCuLink/PCIe_{REF0}_R.CK-": [
        "85Ohm-diff_PCIe"
      ],
      "/OCuLink/PCIe_{REF0}{PCIe_{REF}}": [
        "85Ohm-diff_PCIe"
      ],
      "/OCuLink/PCIe_{x4}.RX0+": [
        "85Ohm-diff_PCIe"
      ],
      "/OCuLink/PCIe_{x4}.RX0-": [
        "85Ohm-diff_PCIe"
      ],
      "/OCuLink/PCIe_{x4}.RX1+": [
        "85Ohm-diff_PCIe"
      ],
      "/OCuLink/PCIe_{x4}.RX1-": [
        "85Ohm-diff_PCIe"
      ],
      "/OCuLink/PCIe_{x4}.RX2+": [
        "85Ohm-diff_PCIe"
      ],
      "/OCuLink/PCIe_{x4}.RX2-": [
        "85Ohm-diff_PCIe"
      ],
      "/OCuLink/PCIe_{x4}.RX3+": [
        "85Ohm-diff_PCIe"
      ],
      "/OCuLink/PCIe_{x4}.RX3-": [
        "85Ohm-diff_PCIe"
      ],
      "/OCuLink/PCIe_{x4}.TX0+": [
        "85Ohm-diff_PCIe"
      ],
      "/OCuLink/PCIe_{x4}.TX0-": [
        "85Ohm-diff_PCIe"
      ],
      "/OCuLink/PCIe_{x4}.TX1+": [
        "85Ohm-diff_PCIe"
      ],
      "/OCuLink/PCIe_{x4}.TX1-": [
        "85Ohm-diff_PCIe"
      ],
      "/OCuLink/PCIe_{x4}.TX2+": [
        "85Ohm-diff_PCIe"
      ],
      "/OCuLink/PCIe_{x4}.TX2-": [
        "85Ohm-diff_PCIe"
      ],
      "/OCuLink/PCIe_{x4}.TX3+": [
        "85Ohm-diff_PCIe"
      ],
      "/OCuLink/PCIe_{x4}.TX3-": [
        "85Ohm-diff_PCIe"
      ],
      "/OCuLink/PCIe_{x4}{PCIe}": [
        "85Ohm-diff_PCIe"
      ],
      "/PCIe-clock-generator/PCIe_{REF1}_R.CK+": [
        "85Ohm-diff_PCIe"
      ],
      "/PCIe-clock-generator/PCIe_{REF1}_R.CK-": [
        "85Ohm-diff_PCIe"
      ],
      "/PCIe-clock-generator/PCIe_{REF1}_R2.CK+": [
        "85Ohm-diff_PCIe"
      ],
      "/PCIe-clock-generator/PCIe_{REF1}_R2.CK-": [
        "85Ohm-diff_PCIe"
      ],
      "/Power/3V3_CONV": [
        "PWR"
      ],
      "/Power/Ideal-diode-1/VIN": [
        "PWR"
      ],
      "/Power/Ideal-diode-2/VIN": [
        "PWR"
      ],
      "/Power/VCC_DC_CONN": [
        "PWR"
      ],
      "/Power/VCC_DC_CONN_1": [
        "PWR"
      ],
      "/Power/VCC_DC_CONN_2": [
        "PWR"
      ],
      "/Power/VCC_PD": [
        "PWR"
      ],
      "/USB-PD/12V_CONV": [
        "PWR"
      ],
      "/USB-PD/VCC": [
        "PWR"
      ],
      "GND": [
        "GND"
      ],
      "VBUS": [
        "PWR"
      ]
    },
    "netclass_patterns": []
  },
  "pcbnew": {
    "last_paths": {
      "gencad": "",
      "idf": "",
      "netlist": "",
      "plot": "",
      "pos_files": "",
      "specctra_dsn": "",
      "step": "",
      "svg": "",
      "vrml": ""
    },
    "page_layout_descr_file": ""
  },
  "schematic": {
    "annotate_start_num": 0,
    "bom_export_filename": "${PROJECTNAME}.csv",
    "bom_fmt_presets": [],
    "bom_fmt_settings": {
      "field_delimiter": ",",
      "keep_line_breaks": false,
      "keep_tabs": false,
      "name": "CSV",
      "ref_delimiter": ",",
      "ref_range_delimiter": "",
      "string_delimiter": "\""
    },
    "bom_presets": [],
    "bom_settings": {
      "exclude_dnp": false,
      "fields_ordered": [
        {
          "group_by": false,
          "label": "Reference",
          "name": "Reference",
          "show": true
        },
        {
          "group_by": false,
          "label": "Qty",
          "name": "${QUANTITY}",
          "show": true
        },
        {
          "group_by": true,
          "label": "Value",
          "name": "Value",
          "show": true
        },
        {
          "group_by": true,
          "label": "DNP",
          "name": "${DNP}",
          "show": true
        },
        {
          "group_by": true,
          "label": "Exclude from BOM",
          "name": "${EXCLUDE_FROM_BOM}",
          "show": true
        },
        {
          "group_by": true,
          "label": "Exclude from Board",
          "name": "${EXCLUDE_FROM_BOARD}",
          "show": true
        },
        {
          "group_by": true,
          "label": "Footprint",
          "name": "Footprint",
          "show": true
        },
        {
          "group_by": false,
          "label": "Datasheet",
          "name": "Datasheet",
          "show": true
        }
      ],
      "filter_string": "",
      "group_symbols": true,
      "include_excluded_from_bom": true,
      "name": "Default Editing",
      "sort_asc": true,
      "sort_field": "Reference"
    },
    "connection_grid_size": 50.0,
    "drawing": {
      "dashed_lines_dash_length_ratio": 12.0,
      "dashed_lines_gap_length_ratio": 3.0,
      "default_line_thickness": 6.0,
      "default_text_size": 50.0,
      "field_names": [],
      "intersheets_ref_own_page": false,
      "intersheets_ref_prefix": "",
      "intersheets_ref_short": false,
      "intersheets_ref_show": false,
      "intersheets_ref_suffix": "",
      "junction_size_choice": 3,
      "label_size_ratio": 0.375,
      "operating_point_overlay_i_precision": 3,
      "operating_point_overlay_i_range": "~A",
      "operating_point_overlay_v_precision": 3,
      "operating_point_overlay_v_range": "~V",
      "overbar_offset_ratio": 1.23,
      "pin_symbol_size": 25.0,
      "text_offset_ratio": 0.15
    },
    "legacy_lib_dir": "",
    "legacy_lib_list": [],
    "meta": {
      "version": 1
    },
    "net_format_name": "",
    "page_layout_descr_file": "",
    "plot_directory": "",
    "space_save_all_events": true,
    "spice_current_sheet_as_root": false,
    "spice_external_command": "spice \"%I\"",
    "spice_model_current_sheet_as_root": true,
    "spice_save_all_currents": false,
    "spice_save_all_dissipations": false,
    "spice_save_all_voltages": false,
    "subpart_first_id": 65,
    "subpart_id_separator": 0
  },
  "sheets": [
    [
      "",
      "Root"
    ],
    [
      "",
      "OCuLink"
    ],
    [
      "",
      "PCIe-connector"
    ],
    [
      "",
      "Power"
    ],
    [
      "",
      "USB-PD"
    ],
    [
      "",
      "Ideal-diode-0"
    ],
    [
      "",
      "Ideal-diode-1"
    ],
    [
      "",
      "PCIe-clock-generator"
    ],
    [
      "",
      "Ideal-diode-2"
    ]
  ],
  "text_variables": {}
}
